# BASEBOARD_FAB2 (Tioga Pass) — schematic netlist excerpt (pin names and nets, part order shuffled) for the footprints in the layout excerpt that follows; sources: Cadence DE-HDL packaged netlist, KiCad conversion of Wiwynn_Tioga_Pass_MB.brd

C5M6  CAP_A  47UF 4V 20% X5R  pkg 0603V  page 220 : A = PVDDQ_DEF ; B = GND
R7P28  RES  150.0 1% CHIP  pkg 0402  page 93 : A = PVCCIO_CPU1 ; B = H_CPU1_PROCHOT_G_N
R2N17  RES  2.7K 1% CHIP  pkg 0402  page 164 : A = P3V3_STBY ; B = FM_BOARD_SKU_ID4

(kicad_pcb
	(version 20260206)
	(generator "pcbnew")
	(generator_version "10.0")
	(general
		(thickness 1.6)
		(legacy_teardrops no)
	)
	(paper "A4")
	(title_block
		(title "Wiwynn_Tioga_Pass_MB.brd")
		(comment 1 "Tioga Pass / footprints 4088-4090 of 4770")
	)
	(layers
		(0 "F.Cu" signal "TOP")
		(4 "In1.Cu" signal "L2GND")
		(6 "In2.Cu" signal "L3")
		(8 "In3.Cu" signal "L4GND")
		(10 "In4.Cu" signal "L5")
		(12 "In5.Cu" signal "L6GND")
		(14 "In6.Cu" signal "L7VCC")
		(16 "In7.Cu" signal "L8VCC")
		(18 "In8.Cu" signal "L9GND")
		(20 "In9.Cu" signal "L10")
		(22 "In10.Cu" signal "L11GND")
		(24 "In11.Cu" signal "L12")
		(26 "In12.Cu" signal "L13GND")
		(2 "B.Cu" signal "BOTTOM")
		(9 "F.Adhes" user "F.Adhesive")
		(11 "B.Adhes" user "B.Adhesive")
		(13 "F.Paste" user "Package Geometry/Pastemask Top")
		(15 "B.Paste" user "Package Geometry/Pastemask Bottom")
		(5 "F.SilkS" user "Ref Des/Silkscreen Top")
		(7 "B.SilkS" user "Ref Des/Silkscreen Bottom")
		(1 "F.Mask" user "Board Geometry/Soldermask Top")
		(3 "B.Mask" user "Board Geometry/Soldermask Bottom")
		(17 "Dwgs.User" user "User.Drawings")
		(19 "Cmts.User" user "User.Comments")
		(21 "Eco1.User" user "User.Eco1")
		(23 "Eco2.User" user "User.Eco2")
		(25 "Edge.Cuts" user "Board Geometry/Outline")
		(27 "Margin" user)
		(31 "F.CrtYd" user "Package Geometry/Place Bound Top")
		(29 "B.CrtYd" user "Package Geometry/Place Bound Bottom")
		(35 "F.Fab" user "Ref Des/Assembly Top")
		(33 "B.Fab" user "Ref Des/Assembly Bottom")
	)
	(footprint ""
		(layer "B.Cu")
		(at 248.8565 -135.4074 -90)
		(property "Reference" "C5M6"
			(at -1.848866 0.752348 270)
			(unlocked yes)
			(layer "B.SilkS")
			(effects
				(font
					(size 1.27 0.9652)
					(thickness 0.1524)
				)
				(justify mirror)
			)
		)
		(property "Value" ""
			(at 0 0 90)
			(layer "B.Fab")
			(effects
				(font
					(size 1.27 1.27)
				)
				(justify mirror)
			)
		)
		(duplicate_pad_numbers_are_jumpers no)
		(fp_rect
			(start 0.500126 1.598422)
			(end -0.500126 -0.201422)
			(stroke
				(width 0)
				(type default)
			)
			(fill no)
			(layer "B.CrtYd")
		)
		(fp_line
			(start -0.500126 1.598422)
			(end 0.500126 1.598422)
			(stroke
				(width 0.1)
				(type default)
			)
			(layer "B.Fab")
		)
		(fp_line
			(start 0.500126 1.598422)
			(end 0.500126 -0.201422)
			(stroke
				(width 0.1)
				(type default)
			)
			(layer "B.Fab")
		)
		(fp_line
			(start -0.500126 -0.201422)
			(end -0.500126 1.598422)
			(stroke
				(width 0.1)
				(type default)
			)
			(layer "B.Fab")
		)
		(fp_line
			(start 0.500126 -0.201422)
			(end -0.500126 -0.201422)
			(stroke
				(width 0.1)
				(type default)
			)
			(layer "B.Fab")
		)
		(pad "1" smd rect
			(at 0 0 180)
			(size 0.889 0.9906)
			(layers "B.Cu" "B.Mask" "B.Paste")
			(net "PVDDQ_DEF")
		)
		(pad "2" smd rect
			(at 0 1.397 180)
			(size 0.889 0.9906)
			(layers "B.Cu" "B.Mask" "B.Paste")
			(net "GND")
		)
		(zone
			(layer "B.Cu")
			(hatch none 0.5)
			(connect_pads
				(clearance 0)
			)
			(min_thickness 0.25)
			(keepout
				(tracks not_allowed)
				(vias allowed)
				(pads allowed)
				(copperpour not_allowed)
				(footprints allowed)
			)
			(placement
				(enabled no)
				(sheetname "")
			)
			(fill
				(thermal_gap 0.5)
				(thermal_bridge_width 0.5)
				(island_removal_mode 0)
			)
			(polygon
				(pts
					(xy 247.904 -134.9121) (xy 248.412 -134.9121) (xy 248.412 -135.9027) (xy 247.904 -135.9027)
				)
			)
		)
		(zone
			(layer "B.Cu")
			(hatch none 0.5)
			(connect_pads
				(clearance 0)
			)
			(min_thickness 0.25)
			(keepout
				(tracks allowed)
				(vias not_allowed)
				(pads allowed)
				(copperpour not_allowed)
				(footprints allowed)
			)
			(placement
				(enabled no)
				(sheetname "")
			)
			(fill
				(thermal_gap 0.5)
				(thermal_bridge_width 0.5)
				(island_removal_mode 0)
			)
			(polygon
				(pts
					(xy 247.904 -134.9121) (xy 248.412 -134.9121) (xy 248.412 -135.9027) (xy 247.904 -135.9027)
				)
			)
		)
	)
	(footprint ""
		(layer "B.Cu")
		(at 405.219408 -92.993718 -90)
		(property "Reference" "R2N17"
			(at 0 0 90)
			(layer "B.SilkS")
			(hide yes)
			(effects
				(font
					(size 1.27 1.27)
				)
				(justify mirror)
			)
		)
		(property "Value" ""
			(at 0 0 90)
			(layer "B.Fab")
			(effects
				(font
					(size 1.27 1.27)
				)
				(justify mirror)
			)
		)
		(duplicate_pad_numbers_are_jumpers no)
		(fp_poly
			(pts
				(xy 0.2794 -0.1016) (xy -0.2794 -0.1016) (xy -0.2794 0.9906) (xy 0.2794 0.9906)
			)
			(stroke
				(width 0)
				(type default)
			)
			(fill no)
			(layer "B.CrtYd")
		)
		(fp_line
			(start -0.2794 0.9906)
			(end -0.2794 -0.1016)
			(stroke
				(width 0.1)
				(type default)
			)
			(layer "B.Fab")
		)
		(fp_line
			(start 0.2794 0.9906)
			(end -0.2794 0.9906)
			(stroke
				(width 0.1)
				(type default)
			)
			(layer "B.Fab")
		)
		(fp_line
			(start -0.2794 -0.1016)
			(end 0.2794 -0.1016)
			(stroke
				(width 0.1)
				(type default)
			)
			(layer "B.Fab")
		)
		(fp_line
			(start 0.2794 -0.1016)
			(end 0.2794 0.9906)
			(stroke
				(width 0.1)
				(type default)
			)
			(layer "B.Fab")
		)
		(pad "1" smd rect
			(at 0 0 90)
			(size 0.508 0.508)
			(layers "B.Cu" "B.Mask" "B.Paste")
			(net "P3V3_STBY")
		)
		(pad "2" smd rect
			(at 0 0.889 90)
			(size 0.508 0.508)
			(layers "B.Cu" "B.Mask" "B.Paste")
			(net "FM_BOARD_SKU_ID4")
		)
		(zone
			(layer "B.Cu")
			(hatch none 0.5)
			(connect_pads
				(clearance 0)
			)
			(min_thickness 0.25)
			(keepout
				(tracks not_allowed)
				(vias allowed)
				(pads allowed)
				(copperpour not_allowed)
				(footprints allowed)
			)
			(placement
				(enabled no)
				(sheetname "")
			)
			(fill
				(thermal_gap 0.5)
				(thermal_bridge_width 0.5)
				(island_removal_mode 0)
			)
			(polygon
				(pts
					(xy 404.584408 -92.739718) (xy 404.584408 -93.247718) (xy 404.965408 -93.247718) (xy 404.965408 -92.739718)
				)
			)
		)
		(zone
			(layer "B.Cu")
			(hatch none 0.5)
			(connect_pads
				(clearance 0)
			)
			(min_thickness 0.25)
			(keepout
				(tracks allowed)
				(vias not_allowed)
				(pads allowed)
				(copperpour not_allowed)
				(footprints allowed)
			)
			(placement
				(enabled no)
				(sheetname "")
			)
			(fill
				(thermal_gap 0.5)
				(thermal_bridge_width 0.5)
				(island_removal_mode 0)
			)
			(polygon
				(pts
					(xy 404.965408 -92.739718) (xy 404.965408 -93.247718) (xy 404.584408 -93.247718) (xy 404.584408 -92.739718)
				)
			)
		)
	)
	(footprint ""
		(layer "B.Cu")
		(at 131.04622 -65.670938 -90)
		(property "Reference" "R7P28"
			(at 0 0 90)
			(layer "B.SilkS")
			(hide yes)
			(effects
				(font
					(size 1.27 1.27)
				)
				(justify mirror)
			)
		)
		(property "Value" ""
			(at 0 0 90)
			(layer "B.Fab")
			(effects
				(font
					(size 1.27 1.27)
				)
				(justify mirror)
			)
		)
		(duplicate_pad_numbers_are_jumpers no)
		(fp_poly
			(pts
				(xy 0.2794 -0.1016) (xy -0.2794 -0.1016) (xy -0.2794 0.9906) (xy 0.2794 0.9906)
			)
			(stroke
				(width 0)
				(type default)
			)
			(fill no)
			(layer "B.CrtYd")
		)
		(fp_line
			(start -0.2794 0.9906)
			(end -0.2794 -0.1016)
			(stroke
				(width 0.1)
				(type default)
			)
			(layer "B.Fab")
		)
		(fp_line
			(start 0.2794 0.9906)
			(end -0.2794 0.9906)
			(stroke
				(width 0.1)
				(type default)
			)
			(layer "B.Fab")
		)
		(fp_line
			(start -0.2794 -0.1016)
			(end 0.2794 -0.1016)
			(stroke
				(width 0.1)
				(type default)
			)
			(layer "B.Fab")
		)
		(fp_line
			(start 0.2794 -0.1016)
			(end 0.2794 0.9906)
			(stroke
				(width 0.1)
				(type default)
			)
			(layer "B.Fab")
		)
		(pad "1" smd rect
			(at 0 0 90)
			(size 0.508 0.508)
			(layers "B.Cu" "B.Mask" "B.Paste")
			(net "PVCCIO_CPU1")
		)
		(pad "2" smd rect
			(at 0 0.889 90)
			(size 0.508 0.508)
			(layers "B.Cu" "B.Mask" "B.Paste")
			(net "H_CPU1_PROCHOT_G_N")
		)
		(zone
			(layer "B.Cu")
			(hatch none 0.5)
			(connect_pads
				(clearance 0)
			)
			(min_thickness 0.25)
			(keepout
				(tracks not_allowed)
				(vias allowed)
				(pads allowed)
				(copperpour not_allowed)
				(footprints allowed)
			)
			(placement
				(enabled no)
				(sheetname "")
			)
			(fill
				(thermal_gap 0.5)
				(thermal_bridge_width 0.5)
				(island_removal_mode 0)
			)
			(polygon
				(pts
					(xy 130.41122 -65.416938) (xy 130.41122 -65.924938) (xy 130.79222 -65.924938) (xy 130.79222 -65.416938)
				)
			)
		)
		(zone
			(layer "B.Cu")
			(hatch none 0.5)
			(connect_pads
				(clearance 0)
			)
			(min_thickness 0.25)
			(keepout
				(tracks allowed)
				(vias not_allowed)
				(pads allowed)
				(copperpour not_allowed)
				(footprints allowed)
			)
			(placement
				(enabled no)
				(sheetname "")
			)
			(fill
				(thermal_gap 0.5)
				(thermal_bridge_width 0.5)
				(island_removal_mode 0)
			)
			(polygon
				(pts
					(xy 130.79222 -65.416938) (xy 130.79222 -65.924938) (xy 130.41122 -65.924938) (xy 130.41122 -65.416938)
				)
			)
		)
	)
)
